(kicad_pcb
	(version 20241229)
	(generator "pcbnew")
	(generator_version "9.0")
	(general
		(thickness 1.6642)
		(legacy_teardrops no)
	)
	(paper "A3")
	(title_block
		(title "PolarFire SoM")
		(date "2025-07-22")
		(rev "1.1.4")
		(company "Antmicro Ltd")
		(comment 1 "www.antmicro.com")
		(comment 9 "footprint 85 of 470 (U1), pads 359-426 of 484")
	)
	(layers
		(0 "F.Cu" mixed)
		(4 "In1.Cu" power)
		(6 "In2.Cu" signal)
		(8 "In3.Cu" power)
		(10 "In4.Cu" signal)
		(12 "In5.Cu" power)
		(14 "In6.Cu" power)
		(16 "In7.Cu" signal)
		(18 "In8.Cu" power)
		(20 "In9.Cu" signal)
		(22 "In10.Cu" power)
		(24 "In11.Cu" signal)
		(26 "In12.Cu" signal)
		(2 "B.Cu" mixed)
		(9 "F.Adhes" user "F.Adhesive")
		(11 "B.Adhes" user "B.Adhesive")
		(13 "F.Paste" user)
		(15 "B.Paste" user)
		(5 "F.SilkS" user "F.Silkscreen")
		(7 "B.SilkS" user "B.Silkscreen")
		(1 "F.Mask" user)
		(3 "B.Mask" user)
		(17 "Dwgs.User" user "User.Drawings")
		(19 "Cmts.User" user "User.Comments")
		(21 "Eco1.User" user "User.Eco1")
		(23 "Eco2.User" user "User.Eco2")
		(25 "Edge.Cuts" user)
		(27 "Margin" user)
		(31 "F.CrtYd" user "F.Courtyard")
		(29 "B.CrtYd" user "B.Courtyard")
		(35 "F.Fab" user)
		(33 "B.Fab" user)
	)
	(footprint "antmicro-footprints:BGA-484_19x19mm_Layout22x22_P0.8mm_FCVG484"
		(layer "F.Cu")
		(at 197.699 132.701 -90)
		(descr "FCVG484, 19.0x19.0mm, 484 Ball, 22x22 Layout, 0.8mm Pitch")
		(tags "BGA 484 0.8")
		(property "Reference" "U1"
			(at 0 -10.8 270)
			(layer "F.SilkS")
			(effects
				(font
					(size 0.7 0.7)
					(thickness 0.15)
				)
				(justify left bottom)
			)
		)
		(property "Value" "MPFS250T-FCVG484"
			(at 0 11.5 270)
			(layer "F.Fab")
			(hide yes)
			(effects
				(font
					(size 0.7 0.7)
					(thickness 0.15)
				)
				(justify left bottom)
			)
		)
		(property "Datasheet" "https://ww1.microchip.com/downloads/aemDocuments/documents/FPGA/ProductDocuments/DataSheets/PolarFire-SoC-Datasheet-DS00004248.pdf"
			(at 0 0 270)
			(layer "F.Fab")
			(hide yes)
			(effects
				(font
					(size 1.27 1.27)
					(thickness 0.15)
				)
			)
		)
		(property "Description" "RISC-V System On Chip (SOC) IC PolarFire® FPGA - 254K Logic Modules 484-FCBGA (19x19)"
			(at 0 0 270)
			(layer "F.Fab")
			(hide yes)
			(effects
				(font
					(size 1.27 1.27)
					(thickness 0.15)
				)
			)
		)
		(property "MPN" "MPFS250T-FCVG484E"
			(at 0 0 270)
			(unlocked yes)
			(layer "F.Fab")
			(hide yes)
			(effects
				(font
					(size 1 1)
					(thickness 0.15)
				)
			)
		)
		(property "Manufacturer" "Microchip Technology"
			(at 0 0 270)
			(unlocked yes)
			(layer "F.Fab")
			(hide yes)
			(effects
				(font
					(size 1 1)
					(thickness 0.15)
				)
			)
		)
		(property "VSD_class" "MPFS250T"
			(at 0 0 270)
			(unlocked yes)
			(layer "F.Fab")
			(hide yes)
			(effects
				(font
					(size 1 1)
					(thickness 0.15)
				)
			)
		)
		(property "Author" "Antmicro"
			(at 0 0 270)
			(unlocked yes)
			(layer "F.Fab")
			(hide yes)
			(effects
				(font
					(size 1 1)
					(thickness 0.15)
				)
			)
		)
		(property "License" "Apache-2.0"
			(at 0 0 270)
			(unlocked yes)
			(layer "F.Fab")
			(hide yes)
			(effects
				(font
					(size 1 1)
					(thickness 0.15)
				)
			)
		)
		(sheetname "/FPGA Config/")
		(sheetfile "fpga-config.kicad_sch")
		(attr smd)
		(pad "R7" smd circle
			(at -3.601 2.799 270)
			(size 0.45 0.45)
			(layers "F.Cu" "F.Mask" "F.Paste")
			(net 2 "+1V1")
			(pinfunction "VDDI6")
			(pintype "passive")
		)
		(pad "R8" smd circle
			(at -2.8 2.799 270)
			(size 0.45 0.45)
			(layers "F.Cu" "F.Mask" "F.Paste")
			(net 584 "/FPGA MSS/LPDDR4.DQ30")
			(pinfunction "MSS_DDR_DQ30")
			(pintype "bidirectional")
			(die_length 7.62709)
		)
		(pad "R9" smd circle
			(at -2 2.799 270)
			(size 0.45 0.45)
			(layers "F.Cu" "F.Mask" "F.Paste")
			(net 418 "+2V5")
			(pinfunction "VDD25")
			(pintype "passive")
		)
		(pad "R10" smd circle
			(at -1.2 2.799 270)
			(size 0.45 0.45)
			(layers "F.Cu" "F.Mask" "F.Paste")
			(net 585 "/FPGA MSS/LPDDR4.DQ29")
			(pinfunction "MSS_DDR_DQ29")
			(pintype "bidirectional")
			(die_length 7.80076)
		)
		(pad "R11" smd circle
			(at -0.401 2.799 270)
			(size 0.45 0.45)
			(layers "F.Cu" "F.Mask" "F.Paste")
			(net 586 "/FPGA MSS/LPDDR4.DQ28")
			(pinfunction "MSS_DDR_DQ28")
			(pintype "bidirectional")
			(die_length 8.72485)
		)
		(pad "R12" smd circle
			(at 0.4 2.799 270)
			(size 0.45 0.45)
			(layers "F.Cu" "F.Mask" "F.Paste")
			(net 436 "unconnected-(U1A-HSIO95PB0{slash}CCC_NW_CLKIN_N_0-PadR12)")
			(pinfunction "HSIO95PB0/CCC_NW_CLKIN_N_0")
			(pintype "bidirectional+no_connect")
			(die_length 7.47419)
		)
		(pad "R13" smd circle
			(at 1.199 2.799 270)
			(size 0.45 0.45)
			(layers "F.Cu" "F.Mask" "F.Paste")
			(net 48 "+1V8")
			(pinfunction "VDD18")
			(pintype "passive")
		)
		(pad "R14" smd circle
			(at 1.999 2.799 270)
			(size 0.45 0.45)
			(layers "F.Cu" "F.Mask" "F.Paste")
			(net 291 "/FPGA HSIO/Crosslink_B1.D9")
			(pinfunction "HSIO77NB0")
			(pintype "bidirectional")
			(die_length 7.79849)
		)
		(pad "R15" smd circle
			(at 2.799 2.799 270)
			(size 0.45 0.45)
			(layers "F.Cu" "F.Mask" "F.Paste")
			(net 292 "/FPGA HSIO/Crosslink_B1.D8")
			(pinfunction "HSIO77PB0")
			(pintype "bidirectional")
			(die_length 7.79503)
		)
		(pad "R16" smd circle
			(at 3.6 2.799 270)
			(size 0.45 0.45)
			(layers "F.Cu" "F.Mask" "F.Paste")
			(net 293 "/FPGA HSIO/Crosslink_B1.D7")
			(pinfunction "HSIO75NB0/DQS")
			(pintype "bidirectional")
			(die_length 7.16841)
		)
		(pad "R17" smd circle
			(at 4.4 2.799 270)
			(size 0.45 0.45)
			(layers "F.Cu" "F.Mask" "F.Paste")
			(net 418 "+2V5")
			(pinfunction "VDD25")
			(pintype "passive")
		)
		(pad "R18" smd circle
			(at 5.2 2.799 270)
			(size 0.45 0.45)
			(layers "F.Cu" "F.Mask" "F.Paste")
			(net 417 "GND")
			(pinfunction "VSS")
			(pintype "passive")
		)
		(pad "R19" smd circle
			(at 5.999 2.799 270)
			(size 0.45 0.45)
			(layers "F.Cu" "F.Mask" "F.Paste")
			(net 142 "/Bottom Connector/PCIE.RXD3_N")
			(pinfunction "XCVR_0_RX3_N")
			(pintype "input")
			(die_length 3.50387)
		)
		(pad "R20" smd circle
			(at 6.799 2.799 270)
			(size 0.45 0.45)
			(layers "F.Cu" "F.Mask" "F.Paste")
			(net 141 "/Bottom Connector/PCIE.RXD3_P")
			(pinfunction "XCVR_0_RX3_P")
			(pintype "input")
			(die_length 3.48923)
		)
		(pad "R21" smd circle
			(at 7.599 2.799 270)
			(size 0.45 0.45)
			(layers "F.Cu" "F.Mask" "F.Paste")
			(net 47 "+1V05")
			(pinfunction "VDDA")
			(pintype "passive")
		)
		(pad "R22" smd circle
			(at 8.4 2.799 270)
			(size 0.45 0.45)
			(layers "F.Cu" "F.Mask" "F.Paste")
			(net 417 "GND")
			(pinfunction "VSS")
			(pintype "passive")
		)
		(pad "T1" smd circle
			(at -8.401 3.6 270)
			(size 0.45 0.45)
			(layers "F.Cu" "F.Mask" "F.Paste")
			(net 437 "unconnected-(U1G-MSS_DDR_CK1{slash}DDR_PLL0_OUT0-PadT1)")
			(pinfunction "MSS_DDR_CK1/DDR_PLL0_OUT0")
			(pintype "bidirectional+no_connect")
			(die_length 4.79804)
		)
		(pad "T2" smd circle
			(at -7.6 3.6 270)
			(size 0.45 0.45)
			(layers "F.Cu" "F.Mask" "F.Paste")
			(net 438 "unconnected-(U1G-MSS_DDR_CK_N1-PadT2)")
			(pinfunction "MSS_DDR_CK_N1")
			(pintype "bidirectional+no_connect")
			(die_length 4.67044)
		)
		(pad "T3" smd circle
			(at -6.8 3.6 270)
			(size 0.45 0.45)
			(layers "F.Cu" "F.Mask" "F.Paste")
			(net 439 "unconnected-(U1G-MSS_DDR_BA1-PadT3)")
			(pinfunction "MSS_DDR_BA1")
			(pintype "bidirectional+no_connect")
			(die_length 4.12005)
		)
		(pad "T4" smd circle
			(at -6 3.6 270)
			(size 0.45 0.45)
			(layers "F.Cu" "F.Mask" "F.Paste")
			(net 2 "+1V1")
			(pinfunction "VDDI6")
			(pintype "passive")
		)
		(pad "T5" smd circle
			(at -5.201 3.6 270)
			(size 0.45 0.45)
			(layers "F.Cu" "F.Mask" "F.Paste")
			(net 587 "/FPGA MSS/LPDDR4.CA0_A")
			(pinfunction "MSS_DDR_A0")
			(pintype "bidirectional")
			(die_length 7.63353)
		)
		(pad "T6" smd circle
			(at -4.401 3.6 270)
			(size 0.45 0.45)
			(layers "F.Cu" "F.Mask" "F.Paste")
			(net 588 "/FPGA MSS/LPDDR4.CA1_A")
			(pinfunction "MSS_DDR_A1")
			(pintype "bidirectional")
			(die_length 8.29046)
		)
		(pad "T7" smd circle
			(at -3.601 3.6 270)
			(size 0.45 0.45)
			(layers "F.Cu" "F.Mask" "F.Paste")
			(net 440 "unconnected-(U1G-MSS_DDR_A7-PadT7)")
			(pinfunction "MSS_DDR_A7")
			(pintype "bidirectional+no_connect")
			(die_length 5.35265)
		)
		(pad "T8" smd circle
			(at -2.8 3.6 270)
			(size 0.45 0.45)
			(layers "F.Cu" "F.Mask" "F.Paste")
			(net 589 "/FPGA MSS/LPDDR4.DQ25")
			(pinfunction "MSS_DDR_DQ25")
			(pintype "bidirectional")
			(die_length 7.08383)
		)
		(pad "T9" smd circle
			(at -2 3.6 270)
			(size 0.45 0.45)
			(layers "F.Cu" "F.Mask" "F.Paste")
			(net 417 "GND")
			(pinfunction "VSS")
			(pintype "passive")
		)
		(pad "T10" smd circle
			(at -1.2 3.6 270)
			(size 0.45 0.45)
			(layers "F.Cu" "F.Mask" "F.Paste")
			(net 590 "/FPGA MSS/LPDDR4.DMI3")
			(pinfunction "MSS_DDR_DM3")
			(pintype "bidirectional")
			(die_length 7.77046)
		)
		(pad "T11" smd circle
			(at -0.401 3.6 270)
			(size 0.45 0.45)
			(layers "F.Cu" "F.Mask" "F.Paste")
			(net 591 "/FPGA MSS/LPDDR4.DQ26")
			(pinfunction "MSS_DDR_DQ26")
			(pintype "bidirectional")
			(die_length 8.39636)
		)
		(pad "T12" smd circle
			(at 0.4 3.6 270)
			(size 0.45 0.45)
			(layers "F.Cu" "F.Mask" "F.Paste")
			(net 441 "unconnected-(U1A-HSIO94NB0-PadT12)")
			(pinfunction "HSIO94NB0")
			(pintype "bidirectional+no_connect")
			(die_length 7.24278)
		)
		(pad "T13" smd circle
			(at 1.199 3.6 270)
			(size 0.45 0.45)
			(layers "F.Cu" "F.Mask" "F.Paste")
			(net 442 "unconnected-(U1A-HSIO95NB0-PadT13)")
			(pinfunction "HSIO95NB0")
			(pintype "bidirectional+no_connect")
			(die_length 7.48434)
		)
		(pad "T14" smd circle
			(at 1.999 3.6 270)
			(size 0.45 0.45)
			(layers "F.Cu" "F.Mask" "F.Paste")
			(net 48 "+1V8")
			(pinfunction "VDDI0")
			(pintype "passive")
		)
		(pad "T15" smd circle
			(at 2.799 3.6 270)
			(size 0.45 0.45)
			(layers "F.Cu" "F.Mask" "F.Paste")
			(net 443 "unconnected-(U1A-HSIO91NB0-PadT15)")
			(pinfunction "HSIO91NB0")
			(pintype "bidirectional+no_connect")
			(die_length 7.08627)
		)
		(pad "T16" smd circle
			(at 3.6 3.6 270)
			(size 0.45 0.45)
			(layers "F.Cu" "F.Mask" "F.Paste")
			(net 294 "/FPGA HSIO/Crosslink_B2.D8")
			(pinfunction "HSIO75PB0/DQS/CCC_NE_PLL1_OUT0")
			(pintype "bidirectional")
			(die_length 7.1755)
		)
		(pad "T17" smd circle
			(at 4.4 3.6 270)
			(size 0.45 0.45)
			(layers "F.Cu" "F.Mask" "F.Paste")
			(net 298 "/FPGA HSIO/Crosslink_B1.D2")
			(pinfunction "HSIO73PB0/CCC_NE_PLL1_OUT1")
			(pintype "bidirectional")
			(die_length 7.13684)
		)
		(pad "T18" smd circle
			(at 5.2 3.6 270)
			(size 0.45 0.45)
			(layers "F.Cu" "F.Mask" "F.Paste")
			(net 417 "GND")
			(pinfunction "VSS")
			(pintype "passive")
		)
		(pad "T19" smd circle
			(at 5.999 3.6 270)
			(size 0.45 0.45)
			(layers "F.Cu" "F.Mask" "F.Paste")
			(net 417 "GND")
			(pinfunction "VSS")
			(pintype "passive")
		)
		(pad "T20" smd circle
			(at 6.799 3.6 270)
			(size 0.45 0.45)
			(layers "F.Cu" "F.Mask" "F.Paste")
			(net 417 "GND")
			(pinfunction "VSS")
			(pintype "passive")
		)
		(pad "T21" smd circle
			(at 7.599 3.6 270)
			(size 0.45 0.45)
			(layers "F.Cu" "F.Mask" "F.Paste")
			(net 66 "/PCIe/XCVR_TX3_N")
			(pinfunction "XCVR_0_TX3_N")
			(pintype "output")
			(die_length 5.78253)
		)
		(pad "T22" smd circle
			(at 8.4 3.6 270)
			(size 0.45 0.45)
			(layers "F.Cu" "F.Mask" "F.Paste")
			(net 91 "/PCIe/XCVR_TX3_P")
			(pinfunction "XCVR_0_TX3_P")
			(pintype "output")
			(die_length 5.76703)
		)
		(pad "U1" smd circle
			(at -8.401 4.4 270)
			(size 0.45 0.45)
			(layers "F.Cu" "F.Mask" "F.Paste")
			(net 2 "+1V1")
			(pinfunction "VDDI6")
			(pintype "passive")
		)
		(pad "U2" smd circle
			(at -7.6 4.4 270)
			(size 0.45 0.45)
			(layers "F.Cu" "F.Mask" "F.Paste")
			(net 444 "unconnected-(U1G-MSS_DDR_A10-PadU2)")
			(pinfunction "MSS_DDR_A10")
			(pintype "bidirectional+no_connect")
			(die_length 5.14531)
		)
		(pad "U3" smd circle
			(at -6.8 4.4 270)
			(size 0.45 0.45)
			(layers "F.Cu" "F.Mask" "F.Paste")
			(net 445 "unconnected-(U1G-MSS_DDR3_WE_N-PadU3)")
			(pinfunction "MSS_DDR3_WE_N")
			(pintype "bidirectional+no_connect")
			(die_length 4.85174)
		)
		(pad "U4" smd circle
			(at -6 4.4 270)
			(size 0.45 0.45)
			(layers "F.Cu" "F.Mask" "F.Paste")
			(net 592 "/FPGA MSS/LPDDR4.CK_N")
			(pinfunction "MSS_DDR_CK_N0")
			(pintype "bidirectional")
			(die_length 6.59715)
		)
		(pad "U5" smd circle
			(at -5.201 4.4 270)
			(size 0.45 0.45)
			(layers "F.Cu" "F.Mask" "F.Paste")
			(net 593 "/FPGA MSS/LPDDR4.CK_P")
			(pinfunction "MSS_DDR_CK0/DDR_PLL0_OUT0")
			(pintype "bidirectional")
			(die_length 7.07391)
		)
		(pad "U6" smd circle
			(at -4.401 4.4 270)
			(size 0.45 0.45)
			(layers "F.Cu" "F.Mask" "F.Paste")
			(net 417 "GND")
			(pinfunction "VSS")
			(pintype "passive")
		)
		(pad "U7" smd circle
			(at -3.601 4.4 270)
			(size 0.45 0.45)
			(layers "F.Cu" "F.Mask" "F.Paste")
			(net 446 "unconnected-(U1G-MSS_DDR_A9-PadU7)")
			(pinfunction "MSS_DDR_A9")
			(pintype "bidirectional+no_connect")
			(die_length 5.68076)
		)
		(pad "U8" smd circle
			(at -2.8 4.4 270)
			(size 0.45 0.45)
			(layers "F.Cu" "F.Mask" "F.Paste")
			(net 594 "/FPGA MSS/LPDDR4.DQ24")
			(pinfunction "MSS_DDR_DQ24")
			(pintype "bidirectional")
			(die_length 7.11722)
		)
		(pad "U9" smd circle
			(at -2 4.4 270)
			(size 0.45 0.45)
			(layers "F.Cu" "F.Mask" "F.Paste")
			(net 595 "/FPGA MSS/LPDDR4.DQS3_P")
			(pinfunction "MSS_DDR_DQS_P3")
			(pintype "bidirectional")
			(die_length 8.22807)
		)
		(pad "U10" smd circle
			(at -1.2 4.4 270)
			(size 0.45 0.45)
			(layers "F.Cu" "F.Mask" "F.Paste")
			(net 596 "/FPGA MSS/LPDDR4.DQ27")
			(pinfunction "MSS_DDR_DQ27")
			(pintype "bidirectional")
			(die_length 7.48606)
		)
		(pad "U11" smd circle
			(at -0.401 4.4 270)
			(size 0.45 0.45)
			(layers "F.Cu" "F.Mask" "F.Paste")
			(net 2 "+1V1")
			(pinfunction "VDDI6")
			(pintype "passive")
		)
		(pad "U12" smd circle
			(at 0.4 4.4 270)
			(size 0.45 0.45)
			(layers "F.Cu" "F.Mask" "F.Paste")
			(net 447 "unconnected-(U1A-HSIO94PB0{slash}CCC_NW_CLKIN_N_1-PadU12)")
			(pinfunction "HSIO94PB0/CCC_NW_CLKIN_N_1")
			(pintype "bidirectional+no_connect")
			(die_length 7.22878)
		)
		(pad "U13" smd circle
			(at 1.199 4.4 270)
			(size 0.45 0.45)
			(layers "F.Cu" "F.Mask" "F.Paste")
			(net 448 "unconnected-(U1A-HSIO93NB0{slash}DQS-PadU13)")
			(pinfunction "HSIO93NB0/DQS")
			(pintype "bidirectional+no_connect")
			(die_length 6.85376)
		)
		(pad "U14" smd circle
			(at 1.999 4.4 270)
			(size 0.45 0.45)
			(layers "F.Cu" "F.Mask" "F.Paste")
			(net 449 "unconnected-(U1A-HSIO93PB0{slash}DQS{slash}CCC_NW_PLL1_OUT0-PadU14)")
			(pinfunction "HSIO93PB0/DQS/CCC_NW_PLL1_OUT0")
			(pintype "bidirectional+no_connect")
			(die_length 6.84078)
		)
		(pad "U15" smd circle
			(at 2.799 4.4 270)
			(size 0.45 0.45)
			(layers "F.Cu" "F.Mask" "F.Paste")
			(net 450 "unconnected-(U1A-HSIO91PB0{slash}CCC_NW_PLL1_OUT1-PadU15)")
			(pinfunction "HSIO91PB0/CCC_NW_PLL1_OUT1")
			(pintype "bidirectional+no_connect")
			(die_length 7.05354)
		)
		(pad "U16" smd circle
			(at 3.6 4.4 270)
			(size 0.45 0.45)
			(layers "F.Cu" "F.Mask" "F.Paste")
			(net 417 "GND")
			(pinfunction "VSS")
			(pintype "passive")
		)
		(pad "U17" smd circle
			(at 4.4 4.4 270)
			(size 0.45 0.45)
			(layers "F.Cu" "F.Mask" "F.Paste")
			(net 299 "/FPGA HSIO/Crosslink_B1.D3")
			(pinfunction "HSIO73NB0")
			(pintype "bidirectional")
			(die_length 7.1737)
		)
		(pad "U18" smd circle
			(at 5.2 4.4 270)
			(size 0.45 0.45)
			(layers "F.Cu" "F.Mask" "F.Paste")
			(net 300 "/FPGA HSIO/Crosslink_B1.D1")
			(pinfunction "HSIO74NB0")
			(pintype "bidirectional")
			(die_length 7.75836)
		)
		(pad "U19" smd circle
			(at 5.999 4.4 270)
			(size 0.45 0.45)
			(layers "F.Cu" "F.Mask" "F.Paste")
			(net 303 "/FPGA HSIO/Crosslink_B1.D0")
			(pinfunction "HSIO74PB0/CLKIN_N_8/CCC_NE_CLKIN_N_8/CCC_NE_PLL1_OUT0")
			(pintype "bidirectional")
			(die_length 7.74846)
		)
		(pad "U20" smd circle
			(at 6.799 4.4 270)
			(size 0.45 0.45)
			(layers "F.Cu" "F.Mask" "F.Paste")
			(net 417 "GND")
			(pinfunction "VSS")
			(pintype "passive")
		)
		(pad "U21" smd circle
			(at 7.599 4.4 270)
			(size 0.45 0.45)
			(layers "F.Cu" "F.Mask" "F.Paste")
			(net 417 "GND")
			(pinfunction "VSS")
			(pintype "passive")
		)
		(pad "U22" smd circle
			(at 8.4 4.4 270)
			(size 0.45 0.45)
			(layers "F.Cu" "F.Mask" "F.Paste")
			(net 417 "GND")
			(pinfunction "VSS")
			(pintype "passive")
		)
		(pad "V1" smd circle
			(at -8.401 5.2 270)
			(size 0.45 0.45)
			(layers "F.Cu" "F.Mask" "F.Paste")
			(net 451 "unconnected-(U1G-MSS_DDR_DQS_N4-PadV1)")
			(pinfunction "MSS_DDR_DQS_N4")
			(pintype "bidirectional+no_connect")
			(die_length 5.02325)
		)
		(pad "V2" smd circle
			(at -7.6 5.2 270)
			(size 0.45 0.45)
			(layers "F.Cu" "F.Mask" "F.Paste")
			(net 452 "unconnected-(U1G-MSS_DDR_DQS_P4-PadV2)")
			(pinfunction "MSS_DDR_DQS_P4")
			(pintype "bidirectional+no_connect")
			(die_length 5.02709)
		)
		(pad "V3" smd circle
			(at -6.8 5.2 270)
			(size 0.45 0.45)
			(layers "F.Cu" "F.Mask" "F.Paste")
			(net 417 "GND")
			(pinfunction "VSS")
			(pintype "passive")
		)
		(pad "V4" smd circle
			(at -6 5.2 270)
			(size 0.45 0.45)
			(layers "F.Cu" "F.Mask" "F.Paste")
			(net 270 "Net-(U1G-MSS_DDR_VREF_IN)")
			(pinfunction "MSS_DDR_VREF_IN")
			(pintype "input")
			(die_length 3.57164)
		)
		(pad "V5" smd circle
			(at -5.201 5.2 270)
			(size 0.45 0.45)
			(layers "F.Cu" "F.Mask" "F.Paste")
			(net 453 "unconnected-(U1G-MSS_DDR_DM4-PadV5)")
			(pinfunction "MSS_DDR_DM4")
			(pintype "bidirectional+no_connect")
			(die_length 4.03998)
		)
		(pad "V6" smd circle
			(at -4.401 5.2 270)
			(size 0.45 0.45)
			(layers "F.Cu" "F.Mask" "F.Paste")
			(net 597 "/FPGA MSS/LPDDR4.CA3_A")
			(pinfunction "MSS_DDR_A3")
			(pintype "bidirectional")
			(die_length 6.53023)
		)
		(pad "V7" smd circle
			(at -3.601 5.2 270)
			(size 0.45 0.45)
			(layers "F.Cu" "F.Mask" "F.Paste")
			(net 598 "/FPGA MSS/LPDDR4.CA2_A")
			(pinfunction "MSS_DDR_A2")
			(pintype "bidirectional")
			(die_length 6.68562)
		)
		(pad "V8" smd circle
			(at -2.8 5.2 270)
			(size 0.45 0.45)
			(layers "F.Cu" "F.Mask" "F.Paste")
			(net 2 "+1V1")
			(pinfunction "VDDI6")
			(pintype "passive")
		)
	)
)
